#ISCELL
  mstr_misc dns *
  *
#ISCELL
  pure_quanta quanta_title_block_c *
  *
#ISCELL
  pure_quanta_power universal_power *
  page137_i160
#CELL
  pure_quanta q_cap *
  page137_i161
#ISCELL
  pure_quanta_power universal_gnd *
  page137_i162
#ISCELL
  pure_quanta_power universal_gnd *
  page137_i163
#CELL
  pure_quanta q_cap *
  page137_i164
#ISCELL
  pure_quanta_power vcc_core *
  page137_i165
#ISCELL
  standard offpage *
  page137_i181
#ISCELL
  standard offpage *
  page137_i182
#ISCELL
  standard offpage *
  page137_i185
#CELL
  pure_quanta q_res *
  page137_i186
#ISCELL
  standard offpage *
  page137_i187
#CELL
  pure_quanta q_res *
  page137_i188
#ISCELL
  standard offpage *
  page137_i189
#ISCELL
  standard offpage *
  page137_i190
#ISCELL
  standard offpage *
  page137_i191
#ISCELL
  standard offpage *
  page137_i192
#CELL
  pure_quanta q_res *
  page137_i193
#CELL
  pure_quanta q_res *
  page137_i194
#ISCELL
  pure_quanta_power universal_power *
  page137_i195
#CELL
  pure_quanta q_cap *
  page137_i196
#ISCELL
  pure_quanta_power universal_gnd *
  page137_i197
#CELL
  pure_quanta q_cap *
  page137_i198
#ISCELL
  pure_quanta_power universal_gnd *
  page137_i199
#ISCELL
  pure_quanta_power vcc_core *
  page137_i200
#ISCELL
  pure_quanta_power vcc_core *
  page137_i201
#CELL
  pure_quanta q_res *
  page137_i202
#ISCELL
  pure_quanta_power vcc_core *
  page137_i203
#CELL
  pure_quanta q_res *
  page137_i204
#ISCELL
  pure_quanta_power vcc_core *
  page137_i205
#CELL
  pure_quanta q_res *
  page137_i206
#ISCELL
  pure_quanta_power vcc_core *
  page137_i207
#CELL
  pure_quanta q_res *
  page137_i208
#ISCELL
  standard offpage *
  page137_i209
#ISCELL
  standard offpage *
  page137_i210
#ISCELL
  standard offpage *
  page137_i211
#ISCELL
  standard offpage *
  page137_i212
#CELL
  pure_quanta pca9617adp *
  page137_i213
#CELL
  pure_quanta pca9617adp *
  page137_i214
#ISCELL
  pure_quanta_power universal_gnd *
  page137_i215
#ISCELL
  pure_quanta_power universal_gnd *
  page137_i216
#CELL
  pure_quanta q_res *
  page137_i217
#CELL
  pure_quanta q_res *
  page137_i218
#CELL
  pure_quanta q_res *
  page137_i219
#CELL
  pure_quanta q_res *
  page137_i220
#CELL
  pure_quanta q_res *
  page137_i221
#ISCELL
  pure_quanta_power vcc_core *
  page137_i222
#ISCELL
  pure_quanta_power vcc_core *
  page137_i223
#CELL
  pure_quanta q_res *
  page137_i224
